# T6G (Grand Teton) — schematic netlist excerpt (pin names and nets, part order shuffled) for the footprints in the layout excerpt that follows; sources: Cadence DE-HDL packaged netlist, KiCad conversion of 04192023_DAF0TMB3IC0_F0TG_MB_C_brd_V02_OCP.brd

C2181  Q_CAP  22UF 4V 20% X6S  pkg C0402  page 69 : A = PVDDCR_CPU0_P0 ; B = GND
R4125  Q_RES  4.7K 5% CHIP  pkg 0402LF  page 125 : A = P3V3_AUX ; B = GPU_3V3IO_RSVD0_FFU_N

(kicad_pcb
	(version 20260206)
	(generator "pcbnew")
	(generator_version "10.0")
	(general
		(thickness 1.6)
		(legacy_teardrops no)
	)
	(paper "A4")
	(title_block
		(title "04192023_DAF0TMB3IC0_F0TG_MB_C_brd_V02_OCP.brd")
		(comment 1 "Grand Teton / footprints 6483-6484 of 8354")
	)
	(layers
		(0 "F.Cu" signal "TOP")
		(4 "In1.Cu" signal "GND")
		(6 "In2.Cu" signal "IN1")
		(8 "In3.Cu" signal "GND1")
		(10 "In4.Cu" signal "IN2")
		(12 "In5.Cu" signal "GND2")
		(14 "In6.Cu" signal "IN3")
		(16 "In7.Cu" signal "GND3")
		(18 "In8.Cu" signal "VCC")
		(20 "In9.Cu" signal "VCC1")
		(22 "In10.Cu" signal "GND4")
		(24 "In11.Cu" signal "IN4")
		(26 "In12.Cu" signal "GND5")
		(28 "In13.Cu" signal "IN5")
		(30 "In14.Cu" signal "GND6")
		(32 "In15.Cu" signal "IN6")
		(34 "In16.Cu" signal "GND7")
		(2 "B.Cu" signal "BOTTOM")
		(9 "F.Adhes" user "F.Adhesive")
		(11 "B.Adhes" user "B.Adhesive")
		(13 "F.Paste" user "Package Geometry/Pastemask Top")
		(15 "B.Paste" user "Package Geometry/Pastemask Bottom")
		(5 "F.SilkS" user "Ref Des/Silkscreen Top")
		(7 "B.SilkS" user "Ref Des/Silkscreen Bottom")
		(1 "F.Mask" user "Board Geometry/Soldermask Top")
		(3 "B.Mask" user "Board Geometry/Soldermask Bottom")
		(17 "Dwgs.User" user "User.Drawings")
		(19 "Cmts.User" user "User.Comments")
		(21 "Eco1.User" user "User.Eco1")
		(23 "Eco2.User" user "User.Eco2")
		(25 "Edge.Cuts" user "Board Geometry/Outline")
		(27 "Margin" user)
		(31 "F.CrtYd" user "Package Geometry/Place Bound Top")
		(29 "B.CrtYd" user "Package Geometry/Place Bound Bottom")
		(35 "F.Fab" user "Ref Des/Assembly Top")
		(33 "B.Fab" user "Ref Des/Assembly Bottom")
	)
	(footprint ""
		(layer "B.Cu")
		(at 372.916958 -248.47931)
		(property "Reference" "C2181"
			(at 0 0 0)
			(layer "B.SilkS")
			(hide yes)
			(effects
				(font
					(size 1.27 1.27)
				)
				(justify mirror)
			)
		)
		(property "Value" ""
			(at 0 0 0)
			(layer "B.Fab")
			(effects
				(font
					(size 1.27 1.27)
				)
				(justify mirror)
			)
		)
		(duplicate_pad_numbers_are_jumpers no)
		(fp_line
			(start -0.7874 -0.4064)
			(end -0.7874 0.4064)
			(stroke
				(width 0.1524)
				(type default)
			)
			(layer "B.SilkS")
		)
		(fp_line
			(start -0.7874 0.4064)
			(end 0.7874 0.4064)
			(stroke
				(width 0.1524)
				(type default)
			)
			(layer "B.SilkS")
		)
		(fp_line
			(start 0.7874 -0.4064)
			(end -0.7874 -0.4064)
			(stroke
				(width 0.1524)
				(type default)
			)
			(layer "B.SilkS")
		)
		(fp_line
			(start 0.7874 0.4064)
			(end 0.7874 -0.4064)
			(stroke
				(width 0.1524)
				(type default)
			)
			(layer "B.SilkS")
		)
		(fp_line
			(start -0.67945 -0.3048)
			(end -0.67945 0.3048)
			(stroke
				(width 0.1)
				(type default)
			)
			(layer "B.Fab")
		)
		(fp_line
			(start -0.67945 0.3048)
			(end -0.120396 0.3048)
			(stroke
				(width 0.1)
				(type default)
			)
			(layer "B.Fab")
		)
		(fp_line
			(start -0.12065 -0.3048)
			(end -0.67945 -0.3048)
			(stroke
				(width 0.1)
				(type default)
			)
			(layer "B.Fab")
		)
		(fp_line
			(start -0.12065 -0.2794)
			(end -0.12065 -0.3048)
			(stroke
				(width 0.1)
				(type default)
			)
			(layer "B.Fab")
		)
		(fp_line
			(start -0.120396 0.2794)
			(end 0.12065 0.2794)
			(stroke
				(width 0.1)
				(type default)
			)
			(layer "B.Fab")
		)
		(fp_line
			(start -0.120396 0.3048)
			(end -0.120396 0.2794)
			(stroke
				(width 0.1)
				(type default)
			)
			(layer "B.Fab")
		)
		(fp_line
			(start 0.12065 -0.305054)
			(end 0.12065 -0.2794)
			(stroke
				(width 0.1)
				(type default)
			)
			(layer "B.Fab")
		)
		(fp_line
			(start 0.12065 -0.2794)
			(end -0.12065 -0.2794)
			(stroke
				(width 0.1)
				(type default)
			)
			(layer "B.Fab")
		)
		(fp_line
			(start 0.12065 0.2794)
			(end 0.12065 0.3048)
			(stroke
				(width 0.1)
				(type default)
			)
			(layer "B.Fab")
		)
		(fp_line
			(start 0.12065 0.3048)
			(end 0.67945 0.3048)
			(stroke
				(width 0.1)
				(type default)
			)
			(layer "B.Fab")
		)
		(fp_line
			(start 0.67945 -0.305054)
			(end 0.12065 -0.305054)
			(stroke
				(width 0.1)
				(type default)
			)
			(layer "B.Fab")
		)
		(fp_line
			(start 0.67945 0.3048)
			(end 0.67945 -0.305054)
			(stroke
				(width 0.1)
				(type default)
			)
			(layer "B.Fab")
		)
		(pad "1" smd circle
			(at 0.40005 0 180)
			(size 0 0)
			(layers "B.Cu" "B.Mask" "B.Paste")
			(net "PVDDCR_CPU0_P0")
		)
		(pad "2" smd circle
			(at -0.40005 0 180)
			(size 0 0)
			(layers "B.Cu" "B.Mask" "B.Paste")
			(net "GND")
		)
	)
	(footprint ""
		(layer "B.Cu")
		(at 163.815268 -415.75101)
		(property "Reference" "R4125"
			(at 0 0 0)
			(layer "B.SilkS")
			(hide yes)
			(effects
				(font
					(size 1.27 1.27)
				)
				(justify mirror)
			)
		)
		(property "Value" ""
			(at 0 0 0)
			(layer "B.Fab")
			(effects
				(font
					(size 1.27 1.27)
				)
				(justify mirror)
			)
		)
		(duplicate_pad_numbers_are_jumpers no)
		(fp_line
			(start -0.7874 -0.4064)
			(end -0.7874 0.4064)
			(stroke
				(width 0.1524)
				(type default)
			)
			(layer "B.SilkS")
		)
		(fp_line
			(start -0.7874 0.4064)
			(end 0.7874 0.4064)
			(stroke
				(width 0.1524)
				(type default)
			)
			(layer "B.SilkS")
		)
		(fp_line
			(start 0.7874 -0.4064)
			(end -0.7874 -0.4064)
			(stroke
				(width 0.1524)
				(type default)
			)
			(layer "B.SilkS")
		)
		(fp_line
			(start 0.7874 0.4064)
			(end 0.7874 -0.4064)
			(stroke
				(width 0.1524)
				(type default)
			)
			(layer "B.SilkS")
		)
		(fp_line
			(start -0.67945 -0.3048)
			(end -0.67945 0.3048)
			(stroke
				(width 0.1)
				(type default)
			)
			(layer "B.Fab")
		)
		(fp_line
			(start -0.67945 0.3048)
			(end -0.120396 0.3048)
			(stroke
				(width 0.1)
				(type default)
			)
			(layer "B.Fab")
		)
		(fp_line
			(start -0.12065 -0.3048)
			(end -0.67945 -0.3048)
			(stroke
				(width 0.1)
				(type default)
			)
			(layer "B.Fab")
		)
		(fp_line
			(start -0.12065 -0.2794)
			(end -0.12065 -0.3048)
			(stroke
				(width 0.1)
				(type default)
			)
			(layer "B.Fab")
		)
		(fp_line
			(start -0.120396 0.2794)
			(end 0.12065 0.2794)
			(stroke
				(width 0.1)
				(type default)
			)
			(layer "B.Fab")
		)
		(fp_line
			(start -0.120396 0.3048)
			(end -0.120396 0.2794)
			(stroke
				(width 0.1)
				(type default)
			)
			(layer "B.Fab")
		)
		(fp_line
			(start 0.12065 -0.305054)
			(end 0.12065 -0.2794)
			(stroke
				(width 0.1)
				(type default)
			)
			(layer "B.Fab")
		)
		(fp_line
			(start 0.12065 -0.2794)
			(end -0.12065 -0.2794)
			(stroke
				(width 0.1)
				(type default)
			)
			(layer "B.Fab")
		)
		(fp_line
			(start 0.12065 0.2794)
			(end 0.12065 0.3048)
			(stroke
				(width 0.1)
				(type default)
			)
			(layer "B.Fab")
		)
		(fp_line
			(start 0.12065 0.3048)
			(end 0.67945 0.3048)
			(stroke
				(width 0.1)
				(type default)
			)
			(layer "B.Fab")
		)
		(fp_line
			(start 0.67945 -0.305054)
			(end 0.12065 -0.305054)
			(stroke
				(width 0.1)
				(type default)
			)
			(layer "B.Fab")
		)
		(fp_line
			(start 0.67945 0.3048)
			(end 0.67945 -0.305054)
			(stroke
				(width 0.1)
				(type default)
			)
			(layer "B.Fab")
		)
		(pad "1" smd circle
			(at 0.40005 0 180)
			(size 0 0)
			(layers "B.Cu" "B.Mask" "B.Paste")
			(net "P3V3_AUX")
		)
		(pad "2" smd circle
			(at -0.40005 0 180)
			(size 0 0)
			(layers "B.Cu" "B.Mask" "B.Paste")
			(net "GPU_3V3IO_RSVD0_FFU_N")
		)
	)
)
